(kicad_pcb
	(version 20260206)
	(generator "pcbnew")
	(generator_version "10.0")
	(general
		(thickness 1.6)
		(legacy_teardrops no)
	)
	(paper "A4")
	(title_block
		(title "01162023_DA0F0TEBIF0_F0T_Expander_BD_F_brd_V02_OCP.brd")
		(comment 1 "Grand Teton / footprints 4950-4957 of 9728")
	)
	(layers
		(0 "F.Cu" signal "TOP")
		(4 "In1.Cu" signal "GND")
		(6 "In2.Cu" signal "VCC")
		(8 "In3.Cu" signal "VCC1")
		(10 "In4.Cu" signal "GND1")
		(12 "In5.Cu" signal "IN1")
		(14 "In6.Cu" signal "GND2")
		(16 "In7.Cu" signal "IN2")
		(18 "In8.Cu" signal "GND3")
		(20 "In9.Cu" signal "IN3")
		(22 "In10.Cu" signal "GND4")
		(24 "In11.Cu" signal "IN4")
		(26 "In12.Cu" signal "GND5")
		(28 "In13.Cu" signal "IN5")
		(30 "In14.Cu" signal "GND6")
		(32 "In15.Cu" signal "IN6")
		(34 "In16.Cu" signal "GND7")
		(2 "B.Cu" signal "BOTTOM")
		(9 "F.Adhes" user "F.Adhesive")
		(11 "B.Adhes" user "B.Adhesive")
		(13 "F.Paste" user "Package Geometry/Pastemask Top")
		(15 "B.Paste" user "Package Geometry/Pastemask Bottom")
		(5 "F.SilkS" user "Ref Des/Silkscreen Top")
		(7 "B.SilkS" user "Ref Des/Silkscreen Bottom")
		(1 "F.Mask" user "Board Geometry/Soldermask Top")
		(3 "B.Mask" user "Board Geometry/Soldermask Bottom")
		(17 "Dwgs.User" user "User.Drawings")
		(19 "Cmts.User" user "User.Comments")
		(21 "Eco1.User" user "User.Eco1")
		(23 "Eco2.User" user "User.Eco2")
		(25 "Edge.Cuts" user "Board Geometry/Outline")
		(27 "Margin" user)
		(31 "F.CrtYd" user "Package Geometry/Place Bound Top")
		(29 "B.CrtYd" user "Package Geometry/Place Bound Bottom")
		(35 "F.Fab" user "Ref Des/Assembly Top")
		(33 "B.Fab" user "Ref Des/Assembly Bottom")
	)
	(footprint ""
		(layer "F.Cu")
		(at 379.754384 -252.356874 -90)
		(property "Reference" "R1429"
			(at 0 0 270)
			(layer "F.SilkS")
			(hide yes)
			(effects
				(font
					(size 1.27 1.27)
				)
			)
		)
		(property "Value" ""
			(at 0 0 270)
			(layer "F.Fab")
			(effects
				(font
					(size 1.27 1.27)
				)
			)
		)
		(duplicate_pad_numbers_are_jumpers no)
		(fp_line
			(start -0.7874 0.4064)
			(end -0.7874 -0.4064)
			(stroke
				(width 0.1524)
				(type default)
			)
			(layer "F.SilkS")
		)
		(fp_line
			(start 0.7874 0.4064)
			(end -0.7874 0.4064)
			(stroke
				(width 0.1524)
				(type default)
			)
			(layer "F.SilkS")
		)
		(fp_line
			(start -0.7874 -0.4064)
			(end 0.7874 -0.4064)
			(stroke
				(width 0.1524)
				(type default)
			)
			(layer "F.SilkS")
		)
		(fp_line
			(start 0.7874 -0.4064)
			(end 0.7874 0.4064)
			(stroke
				(width 0.1524)
				(type default)
			)
			(layer "F.SilkS")
		)
		(fp_line
			(start -0.67945 0.3048)
			(end -0.67945 -0.305054)
			(stroke
				(width 0.1)
				(type default)
			)
			(layer "F.Fab")
		)
		(fp_line
			(start -0.12065 0.3048)
			(end -0.67945 0.3048)
			(stroke
				(width 0.1)
				(type default)
			)
			(layer "F.Fab")
		)
		(fp_line
			(start 0.120396 0.3048)
			(end 0.120396 0.2794)
			(stroke
				(width 0.1)
				(type default)
			)
			(layer "F.Fab")
		)
		(fp_line
			(start 0.67945 0.3048)
			(end 0.120396 0.3048)
			(stroke
				(width 0.1)
				(type default)
			)
			(layer "F.Fab")
		)
		(fp_line
			(start -0.12065 0.2794)
			(end -0.12065 0.3048)
			(stroke
				(width 0.1)
				(type default)
			)
			(layer "F.Fab")
		)
		(fp_line
			(start 0.120396 0.2794)
			(end -0.12065 0.2794)
			(stroke
				(width 0.1)
				(type default)
			)
			(layer "F.Fab")
		)
		(fp_line
			(start -0.12065 -0.2794)
			(end 0.12065 -0.2794)
			(stroke
				(width 0.1)
				(type default)
			)
			(layer "F.Fab")
		)
		(fp_line
			(start 0.12065 -0.2794)
			(end 0.12065 -0.3048)
			(stroke
				(width 0.1)
				(type default)
			)
			(layer "F.Fab")
		)
		(fp_line
			(start 0.12065 -0.3048)
			(end 0.67945 -0.3048)
			(stroke
				(width 0.1)
				(type default)
			)
			(layer "F.Fab")
		)
		(fp_line
			(start 0.67945 -0.3048)
			(end 0.67945 0.3048)
			(stroke
				(width 0.1)
				(type default)
			)
			(layer "F.Fab")
		)
		(fp_line
			(start -0.67945 -0.305054)
			(end -0.12065 -0.305054)
			(stroke
				(width 0.1)
				(type default)
			)
			(layer "F.Fab")
		)
		(fp_line
			(start -0.12065 -0.305054)
			(end -0.12065 -0.2794)
			(stroke
				(width 0.1)
				(type default)
			)
			(layer "F.Fab")
		)
		(pad "1" smd circle
			(at -0.40005 0 270)
			(size 0 0)
			(layers "F.Cu" "F.Mask" "F.Paste")
			(net "GND")
		)
		(pad "2" smd circle
			(at 0.40005 0 270)
			(size 0 0)
			(layers "F.Cu" "F.Mask" "F.Paste")
			(net "PEX3_MODE_SEL4")
		)
	)
	(footprint ""
		(layer "F.Cu")
		(at 152.738328 -122.79884)
		(property "Reference" "C254"
			(at 0 0 0)
			(layer "F.SilkS")
			(hide yes)
			(effects
				(font
					(size 1.27 1.27)
				)
			)
		)
		(property "Value" ""
			(at 0 0 0)
			(layer "F.Fab")
			(effects
				(font
					(size 1.27 1.27)
				)
			)
		)
		(duplicate_pad_numbers_are_jumpers no)
		(fp_line
			(start -0.299974 -0.150114)
			(end 0.299974 -0.150114)
			(stroke
				(width 0.1)
				(type default)
			)
			(layer "F.Fab")
		)
		(fp_line
			(start -0.299974 0.150114)
			(end -0.299974 -0.150114)
			(stroke
				(width 0.1)
				(type default)
			)
			(layer "F.Fab")
		)
		(fp_line
			(start 0.299974 -0.150114)
			(end 0.299974 0.150114)
			(stroke
				(width 0.1)
				(type default)
			)
			(layer "F.Fab")
		)
		(fp_line
			(start 0.299974 0.150114)
			(end -0.299974 0.150114)
			(stroke
				(width 0.1)
				(type default)
			)
			(layer "F.Fab")
		)
		(pad "1" smd rect
			(at -0.2667 0)
			(size 0.3048 0.381)
			(layers "F.Cu" "F.Mask" "F.Paste")
			(net "P5E_PEX1_STN1_TX_DP<26>")
		)
		(pad "2" smd rect
			(at 0.2667 0)
			(size 0.3048 0.381)
			(layers "F.Cu" "F.Mask" "F.Paste")
			(net "P5E_PEX1_STN1_TX_C_DP<26>")
		)
	)
	(footprint ""
		(layer "F.Cu")
		(at 415.487612 -356.244906 90)
		(property "Reference" "C818"
			(at 0 0 90)
			(layer "F.SilkS")
			(hide yes)
			(effects
				(font
					(size 1.27 1.27)
				)
			)
		)
		(property "Value" ""
			(at 0 0 90)
			(layer "F.Fab")
			(effects
				(font
					(size 1.27 1.27)
				)
			)
		)
		(duplicate_pad_numbers_are_jumpers no)
		(fp_line
			(start 0.299974 -0.150114)
			(end 0.299974 0.150114)
			(stroke
				(width 0.1)
				(type default)
			)
			(layer "F.Fab")
		)
		(fp_line
			(start -0.299974 -0.150114)
			(end 0.299974 -0.150114)
			(stroke
				(width 0.1)
				(type default)
			)
			(layer "F.Fab")
		)
		(fp_line
			(start 0.299974 0.150114)
			(end -0.299974 0.150114)
			(stroke
				(width 0.1)
				(type default)
			)
			(layer "F.Fab")
		)
		(fp_line
			(start -0.299974 0.150114)
			(end -0.299974 -0.150114)
			(stroke
				(width 0.1)
				(type default)
			)
			(layer "F.Fab")
		)
		(pad "1" smd rect
			(at -0.2667 0 90)
			(size 0.3048 0.381)
			(layers "F.Cu" "F.Mask" "F.Paste")
			(net "P5E_PEX3_STN7_TX_DP<115>")
		)
		(pad "2" smd rect
			(at 0.2667 0 90)
			(size 0.3048 0.381)
			(layers "F.Cu" "F.Mask" "F.Paste")
			(net "P5E_PEX3_STN7_TX_C_DP<115>")
		)
	)
	(footprint ""
		(layer "F.Cu")
		(at 284.443678 -47.92091)
		(property "Reference" "R603"
			(at 0 0 0)
			(layer "F.SilkS")
			(hide yes)
			(effects
				(font
					(size 1.27 1.27)
				)
			)
		)
		(property "Value" ""
			(at 0 0 0)
			(layer "F.Fab")
			(effects
				(font
					(size 1.27 1.27)
				)
			)
		)
		(duplicate_pad_numbers_are_jumpers no)
		(fp_line
			(start -0.7874 -0.4064)
			(end 0.7874 -0.4064)
			(stroke
				(width 0.1524)
				(type default)
			)
			(layer "F.SilkS")
		)
		(fp_line
			(start -0.7874 0.4064)
			(end -0.7874 -0.4064)
			(stroke
				(width 0.1524)
				(type default)
			)
			(layer "F.SilkS")
		)
		(fp_line
			(start 0.7874 -0.4064)
			(end 0.7874 0.4064)
			(stroke
				(width 0.1524)
				(type default)
			)
			(layer "F.SilkS")
		)
		(fp_line
			(start 0.7874 0.4064)
			(end -0.7874 0.4064)
			(stroke
				(width 0.1524)
				(type default)
			)
			(layer "F.SilkS")
		)
		(fp_line
			(start -0.67945 -0.305054)
			(end -0.12065 -0.305054)
			(stroke
				(width 0.1)
				(type default)
			)
			(layer "F.Fab")
		)
		(fp_line
			(start -0.67945 0.3048)
			(end -0.67945 -0.305054)
			(stroke
				(width 0.1)
				(type default)
			)
			(layer "F.Fab")
		)
		(fp_line
			(start -0.12065 -0.305054)
			(end -0.12065 -0.2794)
			(stroke
				(width 0.1)
				(type default)
			)
			(layer "F.Fab")
		)
		(fp_line
			(start -0.12065 -0.2794)
			(end 0.12065 -0.2794)
			(stroke
				(width 0.1)
				(type default)
			)
			(layer "F.Fab")
		)
		(fp_line
			(start -0.12065 0.2794)
			(end -0.12065 0.3048)
			(stroke
				(width 0.1)
				(type default)
			)
			(layer "F.Fab")
		)
		(fp_line
			(start -0.12065 0.3048)
			(end -0.67945 0.3048)
			(stroke
				(width 0.1)
				(type default)
			)
			(layer "F.Fab")
		)
		(fp_line
			(start 0.120396 0.2794)
			(end -0.12065 0.2794)
			(stroke
				(width 0.1)
				(type default)
			)
			(layer "F.Fab")
		)
		(fp_line
			(start 0.120396 0.3048)
			(end 0.120396 0.2794)
			(stroke
				(width 0.1)
				(type default)
			)
			(layer "F.Fab")
		)
		(fp_line
			(start 0.12065 -0.3048)
			(end 0.67945 -0.3048)
			(stroke
				(width 0.1)
				(type default)
			)
			(layer "F.Fab")
		)
		(fp_line
			(start 0.12065 -0.2794)
			(end 0.12065 -0.3048)
			(stroke
				(width 0.1)
				(type default)
			)
			(layer "F.Fab")
		)
		(fp_line
			(start 0.67945 -0.3048)
			(end 0.67945 0.3048)
			(stroke
				(width 0.1)
				(type default)
			)
			(layer "F.Fab")
		)
		(fp_line
			(start 0.67945 0.3048)
			(end 0.120396 0.3048)
			(stroke
				(width 0.1)
				(type default)
			)
			(layer "F.Fab")
		)
		(pad "1" smd circle
			(at -0.40005 0)
			(size 0 0)
			(layers "F.Cu" "F.Mask" "F.Paste")
			(net "P3V3_AUX")
		)
		(pad "2" smd circle
			(at 0.40005 0)
			(size 0 0)
			(layers "F.Cu" "F.Mask" "F.Paste")
			(net "SSD_8_15_ADC_ALERT_N")
		)
	)
	(footprint ""
		(layer "F.Cu")
		(at 406.36444 -139.6238)
		(property "Reference" "R343"
			(at 0 0 0)
			(layer "F.SilkS")
			(hide yes)
			(effects
				(font
					(size 1.27 1.27)
				)
			)
		)
		(property "Value" ""
			(at 0 0 0)
			(layer "F.Fab")
			(effects
				(font
					(size 1.27 1.27)
				)
			)
		)
		(duplicate_pad_numbers_are_jumpers no)
		(fp_line
			(start -0.7874 -0.4064)
			(end 0.7874 -0.4064)
			(stroke
				(width 0.1524)
				(type default)
			)
			(layer "F.SilkS")
		)
		(fp_line
			(start -0.7874 0.4064)
			(end -0.7874 -0.4064)
			(stroke
				(width 0.1524)
				(type default)
			)
			(layer "F.SilkS")
		)
		(fp_line
			(start 0.7874 -0.4064)
			(end 0.7874 0.4064)
			(stroke
				(width 0.1524)
				(type default)
			)
			(layer "F.SilkS")
		)
		(fp_line
			(start 0.7874 0.4064)
			(end -0.7874 0.4064)
			(stroke
				(width 0.1524)
				(type default)
			)
			(layer "F.SilkS")
		)
		(fp_line
			(start -0.67945 -0.305054)
			(end -0.12065 -0.305054)
			(stroke
				(width 0.1)
				(type default)
			)
			(layer "F.Fab")
		)
		(fp_line
			(start -0.67945 0.3048)
			(end -0.67945 -0.305054)
			(stroke
				(width 0.1)
				(type default)
			)
			(layer "F.Fab")
		)
		(fp_line
			(start -0.12065 -0.305054)
			(end -0.12065 -0.2794)
			(stroke
				(width 0.1)
				(type default)
			)
			(layer "F.Fab")
		)
		(fp_line
			(start -0.12065 -0.2794)
			(end 0.12065 -0.2794)
			(stroke
				(width 0.1)
				(type default)
			)
			(layer "F.Fab")
		)
		(fp_line
			(start -0.12065 0.2794)
			(end -0.12065 0.3048)
			(stroke
				(width 0.1)
				(type default)
			)
			(layer "F.Fab")
		)
		(fp_line
			(start -0.12065 0.3048)
			(end -0.67945 0.3048)
			(stroke
				(width 0.1)
				(type default)
			)
			(layer "F.Fab")
		)
		(fp_line
			(start 0.120396 0.2794)
			(end -0.12065 0.2794)
			(stroke
				(width 0.1)
				(type default)
			)
			(layer "F.Fab")
		)
		(fp_line
			(start 0.120396 0.3048)
			(end 0.120396 0.2794)
			(stroke
				(width 0.1)
				(type default)
			)
			(layer "F.Fab")
		)
		(fp_line
			(start 0.12065 -0.3048)
			(end 0.67945 -0.3048)
			(stroke
				(width 0.1)
				(type default)
			)
			(layer "F.Fab")
		)
		(fp_line
			(start 0.12065 -0.2794)
			(end 0.12065 -0.3048)
			(stroke
				(width 0.1)
				(type default)
			)
			(layer "F.Fab")
		)
		(fp_line
			(start 0.67945 -0.3048)
			(end 0.67945 0.3048)
			(stroke
				(width 0.1)
				(type default)
			)
			(layer "F.Fab")
		)
		(fp_line
			(start 0.67945 0.3048)
			(end 0.120396 0.3048)
			(stroke
				(width 0.1)
				(type default)
			)
			(layer "F.Fab")
		)
		(pad "1" smd circle
			(at -0.40005 0)
			(size 0 0)
			(layers "F.Cu" "F.Mask" "F.Paste")
			(net "RST_SMB_NIC6_MUX_ISO_R_N")
		)
		(pad "2" smd circle
			(at 0.40005 0)
			(size 0 0)
			(layers "F.Cu" "F.Mask" "F.Paste")
			(net "RST_SMB_NIC6_MUX_ISO_N")
		)
	)
	(footprint ""
		(layer "F.Cu")
		(at 138.37158 -152.71115 90)
		(property "Reference" "R705"
			(at 0 0 90)
			(layer "F.SilkS")
			(hide yes)
			(effects
				(font
					(size 1.27 1.27)
				)
			)
		)
		(property "Value" ""
			(at 0 0 90)
			(layer "F.Fab")
			(effects
				(font
					(size 1.27 1.27)
				)
			)
		)
		(duplicate_pad_numbers_are_jumpers no)
		(fp_line
			(start 0.7874 -0.4064)
			(end 0.7874 0.4064)
			(stroke
				(width 0.1524)
				(type default)
			)
			(layer "F.SilkS")
		)
		(fp_line
			(start -0.7874 -0.4064)
			(end 0.7874 -0.4064)
			(stroke
				(width 0.1524)
				(type default)
			)
			(layer "F.SilkS")
		)
		(fp_line
			(start 0.7874 0.4064)
			(end -0.7874 0.4064)
			(stroke
				(width 0.1524)
				(type default)
			)
			(layer "F.SilkS")
		)
		(fp_line
			(start -0.7874 0.4064)
			(end -0.7874 -0.4064)
			(stroke
				(width 0.1524)
				(type default)
			)
			(layer "F.SilkS")
		)
		(fp_line
			(start -0.12065 -0.305054)
			(end -0.12065 -0.2794)
			(stroke
				(width 0.1)
				(type default)
			)
			(layer "F.Fab")
		)
		(fp_line
			(start -0.67945 -0.305054)
			(end -0.12065 -0.305054)
			(stroke
				(width 0.1)
				(type default)
			)
			(layer "F.Fab")
		)
		(fp_line
			(start 0.67945 -0.3048)
			(end 0.67945 0.3048)
			(stroke
				(width 0.1)
				(type default)
			)
			(layer "F.Fab")
		)
		(fp_line
			(start 0.12065 -0.3048)
			(end 0.67945 -0.3048)
			(stroke
				(width 0.1)
				(type default)
			)
			(layer "F.Fab")
		)
		(fp_line
			(start 0.12065 -0.2794)
			(end 0.12065 -0.3048)
			(stroke
				(width 0.1)
				(type default)
			)
			(layer "F.Fab")
		)
		(fp_line
			(start -0.12065 -0.2794)
			(end 0.12065 -0.2794)
			(stroke
				(width 0.1)
				(type default)
			)
			(layer "F.Fab")
		)
		(fp_line
			(start 0.120396 0.2794)
			(end -0.12065 0.2794)
			(stroke
				(width 0.1)
				(type default)
			)
			(layer "F.Fab")
		)
		(fp_line
			(start -0.12065 0.2794)
			(end -0.12065 0.3048)
			(stroke
				(width 0.1)
				(type default)
			)
			(layer "F.Fab")
		)
		(fp_line
			(start 0.67945 0.3048)
			(end 0.120396 0.3048)
			(stroke
				(width 0.1)
				(type default)
			)
			(layer "F.Fab")
		)
		(fp_line
			(start 0.120396 0.3048)
			(end 0.120396 0.2794)
			(stroke
				(width 0.1)
				(type default)
			)
			(layer "F.Fab")
		)
		(fp_line
			(start -0.12065 0.3048)
			(end -0.67945 0.3048)
			(stroke
				(width 0.1)
				(type default)
			)
			(layer "F.Fab")
		)
		(fp_line
			(start -0.67945 0.3048)
			(end -0.67945 -0.305054)
			(stroke
				(width 0.1)
				(type default)
			)
			(layer "F.Fab")
		)
		(pad "1" smd circle
			(at -0.40005 0 90)
			(size 0 0)
			(layers "F.Cu" "F.Mask" "F.Paste")
			(net "NIC2_ADC_A1")
		)
		(pad "2" smd circle
			(at 0.40005 0 90)
			(size 0 0)
			(layers "F.Cu" "F.Mask" "F.Paste")
			(net "P3V3_AUX")
		)
	)
	(footprint ""
		(layer "F.Cu")
		(at 36.638484 -131.323334)
		(property "Reference" "C40"
			(at 0 0 0)
			(layer "F.SilkS")
			(hide yes)
			(effects
				(font
					(size 1.27 1.27)
				)
			)
		)
		(property "Value" ""
			(at 0 0 0)
			(layer "F.Fab")
			(effects
				(font
					(size 1.27 1.27)
				)
			)
		)
		(duplicate_pad_numbers_are_jumpers no)
		(fp_line
			(start -0.299974 -0.150114)
			(end 0.299974 -0.150114)
			(stroke
				(width 0.1)
				(type default)
			)
			(layer "F.Fab")
		)
		(fp_line
			(start -0.299974 0.150114)
			(end -0.299974 -0.150114)
			(stroke
				(width 0.1)
				(type default)
			)
			(layer "F.Fab")
		)
		(fp_line
			(start 0.299974 -0.150114)
			(end 0.299974 0.150114)
			(stroke
				(width 0.1)
				(type default)
			)
			(layer "F.Fab")
		)
		(fp_line
			(start 0.299974 0.150114)
			(end -0.299974 0.150114)
			(stroke
				(width 0.1)
				(type default)
			)
			(layer "F.Fab")
		)
		(pad "1" smd rect
			(at -0.2667 0)
			(size 0.3048 0.381)
			(layers "F.Cu" "F.Mask" "F.Paste")
			(net "P5E_PEX0_STN1_TX_DN<28>")
		)
		(pad "2" smd rect
			(at 0.2667 0)
			(size 0.3048 0.381)
			(layers "F.Cu" "F.Mask" "F.Paste")
			(net "P5E_PEX0_STN1_TX_C_DN<28>")
		)
	)
	(footprint ""
		(layer "F.Cu")
		(at 327.992232 -31.825184 180)
		(property "Reference" "C514"
			(at 0 0 180)
			(layer "F.SilkS")
			(hide yes)
			(effects
				(font
					(size 1.27 1.27)
				)
			)
		)
		(property "Value" ""
			(at 0 0 180)
			(layer "F.Fab")
			(effects
				(font
					(size 1.27 1.27)
				)
			)
		)
		(duplicate_pad_numbers_are_jumpers no)
		(fp_line
			(start 0.299974 0.150114)
			(end -0.299974 0.150114)
			(stroke
				(width 0.1)
				(type default)
			)
			(layer "F.Fab")
		)
		(fp_line
			(start 0.299974 -0.150114)
			(end 0.299974 0.150114)
			(stroke
				(width 0.1)
				(type default)
			)
			(layer "F.Fab")
		)
		(fp_line
			(start -0.299974 0.150114)
			(end -0.299974 -0.150114)
			(stroke
				(width 0.1)
				(type default)
			)
			(layer "F.Fab")
		)
		(fp_line
			(start -0.299974 -0.150114)
			(end 0.299974 -0.150114)
			(stroke
				(width 0.1)
				(type default)
			)
			(layer "F.Fab")
		)
		(pad "1" smd rect
			(at -0.2667 0 180)
			(size 0.3048 0.381)
			(layers "F.Cu" "F.Mask" "F.Paste")
			(net "P5E_PEX2_STN2_TX_DN<34>")
		)
		(pad "2" smd rect
			(at 0.2667 0 180)
			(size 0.3048 0.381)
			(layers "F.Cu" "F.Mask" "F.Paste")
			(net "P5E_PEX2_STN2_TX_C_DN<34>")
		)
	)
)
